(kicad_pcb
	(version 20260206)
	(generator "pcbnew")
	(generator_version "10.0")
	(general
		(thickness 1.6)
		(legacy_teardrops no)
	)
	(paper "A4")
	(title_block
		(title "pdpb — Lightning_PDPB_BRD.brd")
		(comment 1 "Lightning (Wiwynn / Facebook NVMe JBOF) / footprint 592 of 1140 (J17), pads 1-114 of 202")
	)
	(layers
		(0 "F.Cu" signal "TOP")
		(4 "In1.Cu" signal "L2GND")
		(6 "In2.Cu" signal "L3")
		(8 "In3.Cu" signal "L4VCC")
		(10 "In4.Cu" signal "L5VCC")
		(12 "In5.Cu" signal "L6")
		(14 "In6.Cu" signal "L7GND")
		(2 "B.Cu" signal "BOTTOM")
		(9 "F.Adhes" user "F.Adhesive")
		(11 "B.Adhes" user "B.Adhesive")
		(13 "F.Paste" user "Package Geometry/Pastemask Top")
		(15 "B.Paste" user "Package Geometry/Pastemask Bottom")
		(5 "F.SilkS" user "Ref Des/Silkscreen Top")
		(7 "B.SilkS" user "Ref Des/Silkscreen Bottom")
		(1 "F.Mask" user "Board Geometry/Soldermask Top")
		(3 "B.Mask" user "Board Geometry/Soldermask Bottom")
		(17 "Dwgs.User" user "User.Drawings")
		(19 "Cmts.User" user "User.Comments")
		(21 "Eco1.User" user "User.Eco1")
		(23 "Eco2.User" user "User.Eco2")
		(25 "Edge.Cuts" user "Board Geometry/Outline")
		(27 "Margin" user)
		(31 "F.CrtYd" user "Package Geometry/Place Bound Top")
		(29 "B.CrtYd" user "Package Geometry/Place Bound Bottom")
		(35 "F.Fab" user "Ref Des/Assembly Top")
		(33 "B.Fab" user "Ref Des/Assembly Bottom")
	)
	(footprint ""
		(layer "F.Cu")
		(at 2.999994 -425.141898 90)
		(property "Reference" "J17"
			(at 0 0 90)
			(layer "F.SilkS")
			(hide yes)
			(effects
				(font
					(size 1.27 1.27)
				)
			)
		)
		(property "Value" "PCISLT200-5-GP-U"
			(at -48.7045 -6.7818 90)
			(unlocked yes)
			(layer "F.Fab")
			(hide yes)
			(effects
				(font
					(size 1.016 1.016)
					(thickness 0.1524)
				)
			)
		)
		(property "Device Type" "G639F200221431HR-U"
			(at -48.7045 -8.3058 90)
			(unlocked yes)
			(layer "F.Fab")
			(hide yes)
			(effects
				(font
					(size 1.016 1.016)
					(thickness 0.1524)
				)
			)
		)
		(duplicate_pad_numbers_are_jumpers no)
		(pad "" np_thru_hole circle
			(at -47.999904 0 90)
			(size 0.254 0.254)
			(drill 2.2098)
			(layers "*.Cu" "*.Mask")
			(clearance 1.3335)
			(thermal_gap 1.3335)
		)
		(pad "" np_thru_hole circle
			(at 47.999904 0 90)
			(size 0.254 0.254)
			(drill 2.2098)
			(layers "*.Cu" "*.Mask")
			(clearance 1.3335)
			(thermal_gap 1.3335)
		)
		(pad "A1" smd rect
			(at -41.20007 -0.750062 90)
			(size 0.508 2.4892)
			(layers "F.Cu" "F.Mask" "F.Paste")
			(net "GND")
		)
		(pad "A2" smd rect
			(at -40.39997 -0.750062 90)
			(size 0.508 2.4892)
			(layers "F.Cu" "F.Mask" "F.Paste")
			(net "PE_100M_CLK1_C_N")
		)
		(pad "A3" smd rect
			(at -39.600124 -0.750062 90)
			(size 0.508 2.4892)
			(layers "F.Cu" "F.Mask" "F.Paste")
			(net "PE_100M_CLK1_C_P")
		)
		(pad "A4" smd rect
			(at -38.800024 -0.750062 90)
			(size 0.508 2.4892)
			(layers "F.Cu" "F.Mask" "F.Paste")
			(net "GND")
		)
		(pad "A5" smd rect
			(at -37.999924 -0.750062 90)
			(size 0.508 2.4892)
			(layers "F.Cu" "F.Mask" "F.Paste")
			(net "PE_TX1_DR1_N")
		)
		(pad "A6" smd rect
			(at -37.200078 -0.750062 90)
			(size 0.508 2.4892)
			(layers "F.Cu" "F.Mask" "F.Paste")
			(net "PE_TX1_DR1_P")
		)
		(pad "A7" smd rect
			(at -36.399978 -0.750062 90)
			(size 0.508 2.4892)
			(layers "F.Cu" "F.Mask" "F.Paste")
			(net "GND")
		)
		(pad "A8" smd rect
			(at -35.599878 -0.750062 90)
			(size 0.508 2.4892)
			(layers "F.Cu" "F.Mask" "F.Paste")
			(net "GND")
		)
		(pad "A9" smd rect
			(at -34.800032 -0.750062 90)
			(size 0.508 2.4892)
			(layers "F.Cu" "F.Mask" "F.Paste")
			(net "PE_TX2_DR1_N")
		)
		(pad "A10" smd rect
			(at -33.999932 -0.750062 90)
			(size 0.508 2.4892)
			(layers "F.Cu" "F.Mask" "F.Paste")
			(net "PE_TX2_DR1_P")
		)
		(pad "A11" smd rect
			(at -33.200086 -0.750062 90)
			(size 0.508 2.4892)
			(layers "F.Cu" "F.Mask" "F.Paste")
			(net "GND")
		)
		(pad "A12" smd rect
			(at -32.399986 -0.750062 90)
			(size 0.508 2.4892)
			(layers "F.Cu" "F.Mask" "F.Paste")
			(net "GND")
		)
		(pad "A13" smd rect
			(at -31.599886 -0.750062 90)
			(size 0.508 2.4892)
			(layers "F.Cu" "F.Mask" "F.Paste")
			(net "PE_TX3_DR1_N")
		)
		(pad "A14" smd rect
			(at -30.80004 -0.750062 90)
			(size 0.508 2.4892)
			(layers "F.Cu" "F.Mask" "F.Paste")
			(net "PE_TX3_DR1_P")
		)
		(pad "A15" smd rect
			(at -29.99994 -0.750062 90)
			(size 0.508 2.4892)
			(layers "F.Cu" "F.Mask" "F.Paste")
			(net "GND")
		)
		(pad "A16" smd rect
			(at -29.200094 -0.750062 90)
			(size 0.508 2.4892)
			(layers "F.Cu" "F.Mask" "F.Paste")
			(net "GND")
		)
		(pad "A17" smd rect
			(at -28.399994 -0.750062 90)
			(size 0.508 2.4892)
			(layers "F.Cu" "F.Mask" "F.Paste")
			(net "PE_TX4_DR1_N")
		)
		(pad "A18" smd rect
			(at -27.599894 -0.750062 90)
			(size 0.508 2.4892)
			(layers "F.Cu" "F.Mask" "F.Paste")
			(net "PE_TX4_DR1_P")
		)
		(pad "A19" smd rect
			(at -26.800048 -0.750062 90)
			(size 0.508 2.4892)
			(layers "F.Cu" "F.Mask" "F.Paste")
			(net "GND")
		)
		(pad "A20" smd rect
			(at -25.999948 -0.750062 90)
			(size 0.508 2.4892)
			(layers "F.Cu" "F.Mask" "F.Paste")
			(net "SSD1_CLK0_OE_R_N")
		)
		(pad "A21" smd rect
			(at -25.200102 -0.750062 90)
			(size 0.508 2.4892)
			(layers "F.Cu" "F.Mask" "F.Paste")
			(net "ATTN_LED_DR1_N")
		)
		(pad "A22" smd rect
			(at -24.400002 -0.750062 90)
			(size 0.508 2.4892)
			(layers "F.Cu" "F.Mask" "F.Paste")
			(net "SSD1_PWREN")
		)
		(pad "A23" smd rect
			(at -23.599902 -0.750062 90)
			(size 0.508 2.4892)
			(layers "F.Cu" "F.Mask" "F.Paste")
			(net "GND")
		)
		(pad "A24" smd rect
			(at -22.800056 -0.750062 90)
			(size 0.508 2.4892)
			(layers "F.Cu" "F.Mask" "F.Paste")
			(net "PE_TX1_DR10_P")
		)
		(pad "A25" smd rect
			(at -21.999956 -0.750062 90)
			(size 0.508 2.4892)
			(layers "F.Cu" "F.Mask" "F.Paste")
			(net "PE_TX1_DR10_N")
		)
		(pad "A26" smd rect
			(at -21.20011 -0.750062 90)
			(size 0.508 2.4892)
			(layers "F.Cu" "F.Mask" "F.Paste")
			(net "GND")
		)
		(pad "A27" smd rect
			(at -20.40001 -0.750062 90)
			(size 0.508 2.4892)
			(layers "F.Cu" "F.Mask" "F.Paste")
			(net "GND")
		)
		(pad "A28" smd rect
			(at -19.59991 -0.750062 90)
			(size 0.508 2.4892)
			(layers "F.Cu" "F.Mask" "F.Paste")
			(net "PE_TX2_DR10_P")
		)
		(pad "A29" smd rect
			(at -18.800064 -0.750062 90)
			(size 0.508 2.4892)
			(layers "F.Cu" "F.Mask" "F.Paste")
			(net "PE_TX2_DR10_N")
		)
		(pad "A30" smd rect
			(at -17.999964 -0.750062 90)
			(size 0.508 2.4892)
			(layers "F.Cu" "F.Mask" "F.Paste")
			(net "GND")
		)
		(pad "A31" smd rect
			(at -17.200118 -0.750062 90)
			(size 0.508 2.4892)
			(layers "F.Cu" "F.Mask" "F.Paste")
			(net "GND")
		)
		(pad "A32" smd rect
			(at -16.400018 -0.750062 90)
			(size 0.508 2.4892)
			(layers "F.Cu" "F.Mask" "F.Paste")
			(net "PE_TX3_DR10_P")
		)
		(pad "A33" smd rect
			(at -15.599918 -0.750062 90)
			(size 0.508 2.4892)
			(layers "F.Cu" "F.Mask" "F.Paste")
			(net "PE_TX3_DR10_N")
		)
		(pad "A34" smd rect
			(at -14.800072 -0.750062 90)
			(size 0.508 2.4892)
			(layers "F.Cu" "F.Mask" "F.Paste")
			(net "GND")
		)
		(pad "A35" smd rect
			(at -13.999972 -0.750062 90)
			(size 0.508 2.4892)
			(layers "F.Cu" "F.Mask" "F.Paste")
			(net "GND")
		)
		(pad "A36" smd rect
			(at -13.200126 -0.750062 90)
			(size 0.508 2.4892)
			(layers "F.Cu" "F.Mask" "F.Paste")
			(net "PE_TX4_DR10_P")
		)
		(pad "A37" smd rect
			(at -12.400026 -0.750062 90)
			(size 0.508 2.4892)
			(layers "F.Cu" "F.Mask" "F.Paste")
			(net "PE_TX4_DR10_N")
		)
		(pad "A38" smd rect
			(at -11.599926 -0.750062 90)
			(size 0.508 2.4892)
			(layers "F.Cu" "F.Mask" "F.Paste")
			(net "GND")
		)
		(pad "A39" smd rect
			(at -10.80008 -0.750062 90)
			(size 0.508 2.4892)
			(layers "F.Cu" "F.Mask" "F.Paste")
			(net "GND")
		)
		(pad "A40" smd rect
			(at -9.99998 -0.750062 90)
			(size 0.508 2.4892)
			(layers "F.Cu" "F.Mask" "F.Paste")
			(net "PE_TX1_DR0_N")
		)
		(pad "A41" smd rect
			(at -9.19988 -0.750062 90)
			(size 0.508 2.4892)
			(layers "F.Cu" "F.Mask" "F.Paste")
			(net "PE_TX1_DR0_P")
		)
		(pad "A42" smd rect
			(at -8.400034 -0.750062 90)
			(size 0.508 2.4892)
			(layers "F.Cu" "F.Mask" "F.Paste")
			(net "GND")
		)
		(pad "A43" smd rect
			(at -7.599934 -0.750062 90)
			(size 0.508 2.4892)
			(layers "F.Cu" "F.Mask" "F.Paste")
			(net "SSD1_PERST_N")
		)
		(pad "A44" smd rect
			(at -6.800088 -0.750062 90)
			(size 0.508 2.4892)
			(layers "F.Cu" "F.Mask" "F.Paste")
			(net "SSD0_PERST_N")
		)
		(pad "A45" smd rect
			(at -2.800096 -0.750062 90)
			(size 0.508 2.4892)
			(layers "F.Cu" "F.Mask" "F.Paste")
			(net "PWM_EXP_A")
		)
		(pad "A46" smd rect
			(at -1.999996 -0.750062 90)
			(size 0.508 2.4892)
			(layers "F.Cu" "F.Mask" "F.Paste")
			(net "PCIE_MATED#_A")
		)
		(pad "A47" smd rect
			(at -1.199896 -0.750062 90)
			(size 0.508 2.4892)
			(layers "F.Cu" "F.Mask" "F.Paste")
			(net "GND")
		)
		(pad "A48" smd rect
			(at -0.40005 -0.750062 90)
			(size 0.508 2.4892)
			(layers "F.Cu" "F.Mask" "F.Paste")
			(net "PE_TX2_DR0_N")
		)
		(pad "A49" smd rect
			(at 0.40005 -0.750062 90)
			(size 0.508 2.4892)
			(layers "F.Cu" "F.Mask" "F.Paste")
			(net "PE_TX2_DR0_P")
		)
		(pad "A50" smd rect
			(at 1.199896 -0.750062 90)
			(size 0.508 2.4892)
			(layers "F.Cu" "F.Mask" "F.Paste")
			(net "GND")
		)
		(pad "A51" smd rect
			(at 1.999996 -0.750062 90)
			(size 0.508 2.4892)
			(layers "F.Cu" "F.Mask" "F.Paste")
			(net "GND")
		)
		(pad "A52" smd rect
			(at 2.800096 -0.750062 90)
			(size 0.508 2.4892)
			(layers "F.Cu" "F.Mask" "F.Paste")
			(net "PE_TX3_DR0_N")
		)
		(pad "A53" smd rect
			(at 3.599942 -0.750062 90)
			(size 0.508 2.4892)
			(layers "F.Cu" "F.Mask" "F.Paste")
			(net "PE_TX3_DR0_P")
		)
		(pad "A54" smd rect
			(at 4.400042 -0.750062 90)
			(size 0.508 2.4892)
			(layers "F.Cu" "F.Mask" "F.Paste")
			(net "GND")
		)
		(pad "A55" smd rect
			(at 5.199888 -0.750062 90)
			(size 0.508 2.4892)
			(layers "F.Cu" "F.Mask" "F.Paste")
			(net "GND")
		)
		(pad "A56" smd rect
			(at 5.999988 -0.750062 90)
			(size 0.508 2.4892)
			(layers "F.Cu" "F.Mask" "F.Paste")
			(net "PE_TX4_DR0_N")
		)
		(pad "A57" smd rect
			(at 6.800088 -0.750062 90)
			(size 0.508 2.4892)
			(layers "F.Cu" "F.Mask" "F.Paste")
			(net "PE_TX4_DR0_P")
		)
		(pad "A58" smd rect
			(at 7.599934 -0.750062 90)
			(size 0.508 2.4892)
			(layers "F.Cu" "F.Mask" "F.Paste")
			(net "GND")
		)
		(pad "A59" smd rect
			(at 8.400034 -0.750062 90)
			(size 0.508 2.4892)
			(layers "F.Cu" "F.Mask" "F.Paste")
			(net "SSD0_PWREN")
		)
		(pad "A60" smd rect
			(at 9.19988 -0.750062 90)
			(size 0.508 2.4892)
			(layers "F.Cu" "F.Mask" "F.Paste")
			(net "ATTN_LED_DR0_N")
		)
		(pad "A61" smd rect
			(at 9.99998 -0.750062 90)
			(size 0.508 2.4892)
			(layers "F.Cu" "F.Mask" "F.Paste")
			(net "SSD0_CLK0_OE_R_N")
		)
		(pad "A62" smd rect
			(at 10.80008 -0.750062 90)
			(size 0.508 2.4892)
			(layers "F.Cu" "F.Mask" "F.Paste")
			(net "GND")
		)
		(pad "A63" smd rect
			(at 11.599926 -0.750062 90)
			(size 0.508 2.4892)
			(layers "F.Cu" "F.Mask" "F.Paste")
			(net "PE_TX1_DR5_P")
		)
		(pad "A64" smd rect
			(at 12.400026 -0.750062 90)
			(size 0.508 2.4892)
			(layers "F.Cu" "F.Mask" "F.Paste")
			(net "PE_TX1_DR5_N")
		)
		(pad "A65" smd rect
			(at 13.200126 -0.750062 90)
			(size 0.508 2.4892)
			(layers "F.Cu" "F.Mask" "F.Paste")
			(net "GND")
		)
		(pad "A66" smd rect
			(at 13.999972 -0.750062 90)
			(size 0.508 2.4892)
			(layers "F.Cu" "F.Mask" "F.Paste")
			(net "GND")
		)
		(pad "A67" smd rect
			(at 14.800072 -0.750062 90)
			(size 0.508 2.4892)
			(layers "F.Cu" "F.Mask" "F.Paste")
			(net "PE_TX2_DR5_P")
		)
		(pad "A68" smd rect
			(at 15.599918 -0.750062 90)
			(size 0.508 2.4892)
			(layers "F.Cu" "F.Mask" "F.Paste")
			(net "PE_TX2_DR5_N")
		)
		(pad "A69" smd rect
			(at 16.400018 -0.750062 90)
			(size 0.508 2.4892)
			(layers "F.Cu" "F.Mask" "F.Paste")
			(net "GND")
		)
		(pad "A70" smd rect
			(at 17.200118 -0.750062 90)
			(size 0.508 2.4892)
			(layers "F.Cu" "F.Mask" "F.Paste")
			(net "GND")
		)
		(pad "A71" smd rect
			(at 17.999964 -0.750062 90)
			(size 0.508 2.4892)
			(layers "F.Cu" "F.Mask" "F.Paste")
			(net "PE_TX3_DR5_P")
		)
		(pad "A72" smd rect
			(at 18.800064 -0.750062 90)
			(size 0.508 2.4892)
			(layers "F.Cu" "F.Mask" "F.Paste")
			(net "PE_TX3_DR5_N")
		)
		(pad "A73" smd rect
			(at 19.59991 -0.750062 90)
			(size 0.508 2.4892)
			(layers "F.Cu" "F.Mask" "F.Paste")
			(net "GND")
		)
		(pad "A74" smd rect
			(at 20.40001 -0.750062 90)
			(size 0.508 2.4892)
			(layers "F.Cu" "F.Mask" "F.Paste")
			(net "GND")
		)
		(pad "A75" smd rect
			(at 21.20011 -0.750062 90)
			(size 0.508 2.4892)
			(layers "F.Cu" "F.Mask" "F.Paste")
			(net "PE_TX4_DR5_P")
		)
		(pad "A76" smd rect
			(at 21.999956 -0.750062 90)
			(size 0.508 2.4892)
			(layers "F.Cu" "F.Mask" "F.Paste")
			(net "PE_TX4_DR5_N")
		)
		(pad "A77" smd rect
			(at 22.800056 -0.750062 90)
			(size 0.508 2.4892)
			(layers "F.Cu" "F.Mask" "F.Paste")
			(net "GND")
		)
		(pad "A78" smd rect
			(at 23.599902 -0.750062 90)
			(size 0.508 2.4892)
			(layers "F.Cu" "F.Mask" "F.Paste")
			(net "PE_100M_CLK4_C_P")
		)
		(pad "A79" smd rect
			(at 24.400002 -0.750062 90)
			(size 0.508 2.4892)
			(layers "F.Cu" "F.Mask" "F.Paste")
			(net "PE_100M_CLK4_C_N")
		)
		(pad "A80" smd rect
			(at 25.200102 -0.750062 90)
			(size 0.508 2.4892)
			(layers "F.Cu" "F.Mask" "F.Paste")
			(net "GND")
		)
		(pad "A81" smd rect
			(at 25.999948 -0.750062 90)
			(size 0.508 2.4892)
			(layers "F.Cu" "F.Mask" "F.Paste")
			(net "SAS_I2C_B_BUF_SCL_R")
		)
		(pad "A82" smd rect
			(at 26.800048 -0.750062 90)
			(size 0.508 2.4892)
			(layers "F.Cu" "F.Mask" "F.Paste")
			(net "SAS_I2C_B_BUF_SDA_R")
		)
		(pad "A83" smd rect
			(at 27.599894 -0.750062 90)
			(size 0.508 2.4892)
			(layers "F.Cu" "F.Mask" "F.Paste")
			(net "GND")
		)
		(pad "A84" smd rect
			(at 28.399994 -0.750062 90)
			(size 0.508 2.4892)
			(layers "F.Cu" "F.Mask" "F.Paste")
			(net "BMC_I2C_SCL_BUF_9")
		)
		(pad "A85" smd rect
			(at 29.200094 -0.750062 90)
			(size 0.508 2.4892)
			(layers "F.Cu" "F.Mask" "F.Paste")
			(net "BMC_I2C_SDA_BUF_9")
		)
		(pad "A86" smd rect
			(at 29.99994 -0.750062 90)
			(size 0.508 2.4892)
			(layers "F.Cu" "F.Mask" "F.Paste")
			(net "GND")
		)
		(pad "A87" smd rect
			(at 30.80004 -0.750062 90)
			(size 0.508 2.4892)
			(layers "F.Cu" "F.Mask" "F.Paste")
			(net "SAS_I2C_C_BUF_SCL_R")
		)
		(pad "A88" smd rect
			(at 31.599886 -0.750062 90)
			(size 0.508 2.4892)
			(layers "F.Cu" "F.Mask" "F.Paste")
			(net "SAS_I2C_C_BUF_SDA_R")
		)
		(pad "A89" smd rect
			(at 32.399986 -0.750062 90)
			(size 0.508 2.4892)
			(layers "F.Cu" "F.Mask" "F.Paste")
			(net "GND")
		)
		(pad "A90" smd rect
			(at 33.200086 -0.750062 90)
			(size 0.508 2.4892)
			(layers "F.Cu" "F.Mask" "F.Paste")
			(net "GND")
		)
		(pad "A91" smd rect
			(at 33.999932 -0.750062 90)
			(size 0.508 2.4892)
			(layers "F.Cu" "F.Mask" "F.Paste")
			(net "GND")
		)
		(pad "A92" smd rect
			(at 34.800032 -0.750062 90)
			(size 0.508 2.4892)
			(layers "F.Cu" "F.Mask" "F.Paste")
			(net "GND")
		)
		(pad "A93" smd rect
			(at 35.599878 -0.750062 90)
			(size 0.508 2.4892)
			(layers "F.Cu" "F.Mask" "F.Paste")
			(net "GND")
		)
		(pad "A94" smd rect
			(at 36.399978 -0.750062 90)
			(size 0.508 2.4892)
			(layers "F.Cu" "F.Mask" "F.Paste")
			(net "GND")
		)
		(pad "A95" smd rect
			(at 37.200078 -0.750062 90)
			(size 0.508 2.4892)
			(layers "F.Cu" "F.Mask" "F.Paste")
			(net "P12V")
		)
		(pad "A96" smd rect
			(at 37.999924 -0.750062 90)
			(size 0.508 2.4892)
			(layers "F.Cu" "F.Mask" "F.Paste")
			(net "P12V")
		)
		(pad "A97" smd rect
			(at 38.800024 -0.750062 90)
			(size 0.508 2.4892)
			(layers "F.Cu" "F.Mask" "F.Paste")
			(net "P12V")
		)
		(pad "A98" smd rect
			(at 39.600124 -0.750062 90)
			(size 0.508 2.4892)
			(layers "F.Cu" "F.Mask" "F.Paste")
			(net "P12V")
		)
		(pad "A99" smd rect
			(at 40.39997 -0.750062 90)
			(size 0.508 2.4892)
			(layers "F.Cu" "F.Mask" "F.Paste")
			(net "P12V")
		)
		(pad "A100" smd rect
			(at 41.20007 -0.750062 90)
			(size 0.508 2.4892)
			(layers "F.Cu" "F.Mask" "F.Paste")
			(net "P12V")
		)
		(pad "B1" smd rect
			(at -41.20007 -1.131062 90)
			(size 0.508 2.4892)
			(drill
				(offset 0 0.381)
			)
			(layers "F.Cu" "F.Mask" "F.Paste")
			(net "GND")
		)
		(pad "B2" smd rect
			(at -40.39997 -1.131062 90)
			(size 0.508 2.4892)
			(drill
				(offset 0 0.381)
			)
			(layers "F.Cu" "F.Mask" "F.Paste")
			(net "PE_100M_CLK2_C_P")
		)
		(pad "B3" smd rect
			(at -39.600124 -1.131062 90)
			(size 0.508 2.4892)
			(drill
				(offset 0 0.381)
			)
			(layers "F.Cu" "F.Mask" "F.Paste")
			(net "PE_100M_CLK2_C_N")
		)
		(pad "B4" smd rect
			(at -38.800024 -1.131062 90)
			(size 0.508 2.4892)
			(drill
				(offset 0 0.381)
			)
			(layers "F.Cu" "F.Mask" "F.Paste")
			(net "GND")
		)
		(pad "B5" smd rect
			(at -37.999924 -1.131062 90)
			(size 0.508 2.4892)
			(drill
				(offset 0 0.381)
			)
			(layers "F.Cu" "F.Mask" "F.Paste")
			(net "SSD10_PERST_N")
		)
		(pad "B6" smd rect
			(at -37.200078 -1.131062 90)
			(size 0.508 2.4892)
			(drill
				(offset 0 0.381)
			)
			(layers "F.Cu" "F.Mask" "F.Paste")
			(net "GND")
		)
		(pad "B7" smd rect
			(at -36.399978 -1.131062 90)
			(size 0.508 2.4892)
			(drill
				(offset 0 0.381)
			)
			(layers "F.Cu" "F.Mask" "F.Paste")
			(net "PE_RX1_DR1_N")
		)
		(pad "B8" smd rect
			(at -35.599878 -1.131062 90)
			(size 0.508 2.4892)
			(drill
				(offset 0 0.381)
			)
			(layers "F.Cu" "F.Mask" "F.Paste")
			(net "PE_RX1_DR1_P")
		)
		(pad "B9" smd rect
			(at -34.800032 -1.131062 90)
			(size 0.508 2.4892)
			(drill
				(offset 0 0.381)
			)
			(layers "F.Cu" "F.Mask" "F.Paste")
			(net "GND")
		)
		(pad "B10" smd rect
			(at -33.999932 -1.131062 90)
			(size 0.508 2.4892)
			(drill
				(offset 0 0.381)
			)
			(layers "F.Cu" "F.Mask" "F.Paste")
			(net "GND")
		)
		(pad "B11" smd rect
			(at -33.200086 -1.131062 90)
			(size 0.508 2.4892)
			(drill
				(offset 0 0.381)
			)
			(layers "F.Cu" "F.Mask" "F.Paste")
			(net "PE_RX2_DR1_N")
		)
		(pad "B12" smd rect
			(at -32.399986 -1.131062 90)
			(size 0.508 2.4892)
			(drill
				(offset 0 0.381)
			)
			(layers "F.Cu" "F.Mask" "F.Paste")
			(net "PE_RX2_DR1_P")
		)
	)
)
